(kicad_pcb
	(version 20260206)
	(generator "pcbnew")
	(generator_version "10.0")
	(general
		(thickness 1.6)
		(legacy_teardrops no)
	)
	(paper "A4")
	(title_block
		(title "01162023_DA0F0TEBIF0_F0T_Expander_BD_F_brd_V02_OCP.brd")
		(comment 1 "Grand Teton / footprints 5281-5287 of 9728")
	)
	(layers
		(0 "F.Cu" signal "TOP")
		(4 "In1.Cu" signal "GND")
		(6 "In2.Cu" signal "VCC")
		(8 "In3.Cu" signal "VCC1")
		(10 "In4.Cu" signal "GND1")
		(12 "In5.Cu" signal "IN1")
		(14 "In6.Cu" signal "GND2")
		(16 "In7.Cu" signal "IN2")
		(18 "In8.Cu" signal "GND3")
		(20 "In9.Cu" signal "IN3")
		(22 "In10.Cu" signal "GND4")
		(24 "In11.Cu" signal "IN4")
		(26 "In12.Cu" signal "GND5")
		(28 "In13.Cu" signal "IN5")
		(30 "In14.Cu" signal "GND6")
		(32 "In15.Cu" signal "IN6")
		(34 "In16.Cu" signal "GND7")
		(2 "B.Cu" signal "BOTTOM")
		(9 "F.Adhes" user "F.Adhesive")
		(11 "B.Adhes" user "B.Adhesive")
		(13 "F.Paste" user "Package Geometry/Pastemask Top")
		(15 "B.Paste" user "Package Geometry/Pastemask Bottom")
		(5 "F.SilkS" user "Ref Des/Silkscreen Top")
		(7 "B.SilkS" user "Ref Des/Silkscreen Bottom")
		(1 "F.Mask" user "Board Geometry/Soldermask Top")
		(3 "B.Mask" user "Board Geometry/Soldermask Bottom")
		(17 "Dwgs.User" user "User.Drawings")
		(19 "Cmts.User" user "User.Comments")
		(21 "Eco1.User" user "User.Eco1")
		(23 "Eco2.User" user "User.Eco2")
		(25 "Edge.Cuts" user "Board Geometry/Outline")
		(27 "Margin" user)
		(31 "F.CrtYd" user "Package Geometry/Place Bound Top")
		(29 "B.CrtYd" user "Package Geometry/Place Bound Bottom")
		(35 "F.Fab" user "Ref Des/Assembly Top")
		(33 "B.Fab" user "Ref Des/Assembly Bottom")
	)
	(footprint ""
		(layer "F.Cu")
		(at 336.042 -162.814)
		(property "Reference" "R4799"
			(at 0 0 0)
			(layer "F.SilkS")
			(hide yes)
			(effects
				(font
					(size 1.27 1.27)
				)
			)
		)
		(property "Value" ""
			(at 0 0 0)
			(layer "F.Fab")
			(effects
				(font
					(size 1.27 1.27)
				)
			)
		)
		(duplicate_pad_numbers_are_jumpers no)
		(fp_line
			(start -0.7874 -0.4064)
			(end 0.7874 -0.4064)
			(stroke
				(width 0.1524)
				(type default)
			)
			(layer "F.SilkS")
		)
		(fp_line
			(start -0.7874 0.4064)
			(end -0.7874 -0.4064)
			(stroke
				(width 0.1524)
				(type default)
			)
			(layer "F.SilkS")
		)
		(fp_line
			(start 0.7874 -0.4064)
			(end 0.7874 0.4064)
			(stroke
				(width 0.1524)
				(type default)
			)
			(layer "F.SilkS")
		)
		(fp_line
			(start 0.7874 0.4064)
			(end -0.7874 0.4064)
			(stroke
				(width 0.1524)
				(type default)
			)
			(layer "F.SilkS")
		)
		(fp_line
			(start -0.67945 -0.305054)
			(end -0.12065 -0.305054)
			(stroke
				(width 0.1)
				(type default)
			)
			(layer "F.Fab")
		)
		(fp_line
			(start -0.67945 0.3048)
			(end -0.67945 -0.305054)
			(stroke
				(width 0.1)
				(type default)
			)
			(layer "F.Fab")
		)
		(fp_line
			(start -0.12065 -0.305054)
			(end -0.12065 -0.2794)
			(stroke
				(width 0.1)
				(type default)
			)
			(layer "F.Fab")
		)
		(fp_line
			(start -0.12065 -0.2794)
			(end 0.12065 -0.2794)
			(stroke
				(width 0.1)
				(type default)
			)
			(layer "F.Fab")
		)
		(fp_line
			(start -0.12065 0.2794)
			(end -0.12065 0.3048)
			(stroke
				(width 0.1)
				(type default)
			)
			(layer "F.Fab")
		)
		(fp_line
			(start -0.12065 0.3048)
			(end -0.67945 0.3048)
			(stroke
				(width 0.1)
				(type default)
			)
			(layer "F.Fab")
		)
		(fp_line
			(start 0.120396 0.2794)
			(end -0.12065 0.2794)
			(stroke
				(width 0.1)
				(type default)
			)
			(layer "F.Fab")
		)
		(fp_line
			(start 0.120396 0.3048)
			(end 0.120396 0.2794)
			(stroke
				(width 0.1)
				(type default)
			)
			(layer "F.Fab")
		)
		(fp_line
			(start 0.12065 -0.3048)
			(end 0.67945 -0.3048)
			(stroke
				(width 0.1)
				(type default)
			)
			(layer "F.Fab")
		)
		(fp_line
			(start 0.12065 -0.2794)
			(end 0.12065 -0.3048)
			(stroke
				(width 0.1)
				(type default)
			)
			(layer "F.Fab")
		)
		(fp_line
			(start 0.67945 -0.3048)
			(end 0.67945 0.3048)
			(stroke
				(width 0.1)
				(type default)
			)
			(layer "F.Fab")
		)
		(fp_line
			(start 0.67945 0.3048)
			(end 0.120396 0.3048)
			(stroke
				(width 0.1)
				(type default)
			)
			(layer "F.Fab")
		)
		(pad "1" smd circle
			(at -0.40005 0)
			(size 0 0)
			(layers "F.Cu" "F.Mask" "F.Paste")
			(net "PEX3_PCA9555_INT_N")
		)
		(pad "2" smd circle
			(at 0.40005 0)
			(size 0 0)
			(layers "F.Cu" "F.Mask" "F.Paste")
			(net "PEX3_PCA9555_0_INT_N")
		)
	)
	(footprint ""
		(layer "F.Cu")
		(at 271.480534 -125.519942)
		(property "Reference" "C464"
			(at 0 0 0)
			(layer "F.SilkS")
			(hide yes)
			(effects
				(font
					(size 1.27 1.27)
				)
			)
		)
		(property "Value" ""
			(at 0 0 0)
			(layer "F.Fab")
			(effects
				(font
					(size 1.27 1.27)
				)
			)
		)
		(duplicate_pad_numbers_are_jumpers no)
		(fp_line
			(start -0.299974 -0.150114)
			(end 0.299974 -0.150114)
			(stroke
				(width 0.1)
				(type default)
			)
			(layer "F.Fab")
		)
		(fp_line
			(start -0.299974 0.150114)
			(end -0.299974 -0.150114)
			(stroke
				(width 0.1)
				(type default)
			)
			(layer "F.Fab")
		)
		(fp_line
			(start 0.299974 -0.150114)
			(end 0.299974 0.150114)
			(stroke
				(width 0.1)
				(type default)
			)
			(layer "F.Fab")
		)
		(fp_line
			(start 0.299974 0.150114)
			(end -0.299974 0.150114)
			(stroke
				(width 0.1)
				(type default)
			)
			(layer "F.Fab")
		)
		(pad "1" smd rect
			(at -0.2667 0)
			(size 0.3048 0.381)
			(layers "F.Cu" "F.Mask" "F.Paste")
			(net "P5E_PEX2_STN1_TX_DP<27>")
		)
		(pad "2" smd rect
			(at 0.2667 0)
			(size 0.3048 0.381)
			(layers "F.Cu" "F.Mask" "F.Paste")
			(net "P5E_PEX2_STN1_TX_C_DP<27>")
		)
	)
	(footprint ""
		(layer "F.Cu")
		(at 46.673008 -22.867366 90)
		(property "Reference" "C3879"
			(at 0 0 90)
			(layer "F.SilkS")
			(hide yes)
			(effects
				(font
					(size 1.27 1.27)
				)
			)
		)
		(property "Value" ""
			(at 0 0 90)
			(layer "F.Fab")
			(effects
				(font
					(size 1.27 1.27)
				)
			)
		)
		(duplicate_pad_numbers_are_jumpers no)
		(fp_line
			(start 0.7874 -0.4064)
			(end 0.7874 0.4064)
			(stroke
				(width 0.1524)
				(type default)
			)
			(layer "F.SilkS")
		)
		(fp_line
			(start -0.7874 -0.4064)
			(end 0.7874 -0.4064)
			(stroke
				(width 0.1524)
				(type default)
			)
			(layer "F.SilkS")
		)
		(fp_line
			(start 0.7874 0.4064)
			(end -0.7874 0.4064)
			(stroke
				(width 0.1524)
				(type default)
			)
			(layer "F.SilkS")
		)
		(fp_line
			(start -0.7874 0.4064)
			(end -0.7874 -0.4064)
			(stroke
				(width 0.1524)
				(type default)
			)
			(layer "F.SilkS")
		)
		(fp_line
			(start -0.12065 -0.305054)
			(end -0.12065 -0.2794)
			(stroke
				(width 0.1)
				(type default)
			)
			(layer "F.Fab")
		)
		(fp_line
			(start -0.67945 -0.305054)
			(end -0.12065 -0.305054)
			(stroke
				(width 0.1)
				(type default)
			)
			(layer "F.Fab")
		)
		(fp_line
			(start 0.67945 -0.3048)
			(end 0.67945 0.3048)
			(stroke
				(width 0.1)
				(type default)
			)
			(layer "F.Fab")
		)
		(fp_line
			(start 0.12065 -0.3048)
			(end 0.67945 -0.3048)
			(stroke
				(width 0.1)
				(type default)
			)
			(layer "F.Fab")
		)
		(fp_line
			(start 0.12065 -0.2794)
			(end 0.12065 -0.3048)
			(stroke
				(width 0.1)
				(type default)
			)
			(layer "F.Fab")
		)
		(fp_line
			(start -0.12065 -0.2794)
			(end 0.12065 -0.2794)
			(stroke
				(width 0.1)
				(type default)
			)
			(layer "F.Fab")
		)
		(fp_line
			(start 0.120396 0.2794)
			(end -0.12065 0.2794)
			(stroke
				(width 0.1)
				(type default)
			)
			(layer "F.Fab")
		)
		(fp_line
			(start -0.12065 0.2794)
			(end -0.12065 0.3048)
			(stroke
				(width 0.1)
				(type default)
			)
			(layer "F.Fab")
		)
		(fp_line
			(start 0.67945 0.3048)
			(end 0.120396 0.3048)
			(stroke
				(width 0.1)
				(type default)
			)
			(layer "F.Fab")
		)
		(fp_line
			(start 0.120396 0.3048)
			(end 0.120396 0.2794)
			(stroke
				(width 0.1)
				(type default)
			)
			(layer "F.Fab")
		)
		(fp_line
			(start -0.12065 0.3048)
			(end -0.67945 0.3048)
			(stroke
				(width 0.1)
				(type default)
			)
			(layer "F.Fab")
		)
		(fp_line
			(start -0.67945 0.3048)
			(end -0.67945 -0.305054)
			(stroke
				(width 0.1)
				(type default)
			)
			(layer "F.Fab")
		)
		(pad "1" smd circle
			(at -0.40005 0 90)
			(size 0 0)
			(layers "F.Cu" "F.Mask" "F.Paste")
			(net "P12V_SSD1")
		)
		(pad "2" smd circle
			(at 0.40005 0 90)
			(size 0 0)
			(layers "F.Cu" "F.Mask" "F.Paste")
			(net "GND")
		)
	)
	(footprint ""
		(layer "F.Cu")
		(at 286.525462 -343.952322 90)
		(property "Reference" "C2357"
			(at 0 0 90)
			(layer "F.SilkS")
			(hide yes)
			(effects
				(font
					(size 1.27 1.27)
				)
			)
		)
		(property "Value" ""
			(at 0 0 90)
			(layer "F.Fab")
			(effects
				(font
					(size 1.27 1.27)
				)
			)
		)
		(duplicate_pad_numbers_are_jumpers no)
		(fp_line
			(start 0.299974 -0.150114)
			(end 0.299974 0.150114)
			(stroke
				(width 0.1)
				(type default)
			)
			(layer "F.Fab")
		)
		(fp_line
			(start -0.299974 -0.150114)
			(end 0.299974 -0.150114)
			(stroke
				(width 0.1)
				(type default)
			)
			(layer "F.Fab")
		)
		(fp_line
			(start 0.299974 0.150114)
			(end -0.299974 0.150114)
			(stroke
				(width 0.1)
				(type default)
			)
			(layer "F.Fab")
		)
		(fp_line
			(start -0.299974 0.150114)
			(end -0.299974 -0.150114)
			(stroke
				(width 0.1)
				(type default)
			)
			(layer "F.Fab")
		)
		(pad "1" smd rect
			(at -0.2667 0 90)
			(size 0.3048 0.381)
			(layers "F.Cu" "F.Mask" "F.Paste")
			(net "P5E_PEX2_STN4_TX_DP<71>")
		)
		(pad "2" smd rect
			(at 0.2667 0 90)
			(size 0.3048 0.381)
			(layers "F.Cu" "F.Mask" "F.Paste")
			(net "P5E_PEX2_STN4_TX_C_DP<71>")
		)
	)
	(footprint ""
		(layer "F.Cu")
		(at 361.188 -172.974 180)
		(property "Reference" "R4711"
			(at 0 0 180)
			(layer "F.SilkS")
			(hide yes)
			(effects
				(font
					(size 1.27 1.27)
				)
			)
		)
		(property "Value" ""
			(at 0 0 180)
			(layer "F.Fab")
			(effects
				(font
					(size 1.27 1.27)
				)
			)
		)
		(duplicate_pad_numbers_are_jumpers no)
		(fp_line
			(start 0.7874 0.4064)
			(end -0.7874 0.4064)
			(stroke
				(width 0.1524)
				(type default)
			)
			(layer "F.SilkS")
		)
		(fp_line
			(start 0.7874 -0.4064)
			(end 0.7874 0.4064)
			(stroke
				(width 0.1524)
				(type default)
			)
			(layer "F.SilkS")
		)
		(fp_line
			(start -0.7874 0.4064)
			(end -0.7874 -0.4064)
			(stroke
				(width 0.1524)
				(type default)
			)
			(layer "F.SilkS")
		)
		(fp_line
			(start -0.7874 -0.4064)
			(end 0.7874 -0.4064)
			(stroke
				(width 0.1524)
				(type default)
			)
			(layer "F.SilkS")
		)
		(fp_line
			(start 0.67945 0.3048)
			(end 0.120396 0.3048)
			(stroke
				(width 0.1)
				(type default)
			)
			(layer "F.Fab")
		)
		(fp_line
			(start 0.67945 -0.3048)
			(end 0.67945 0.3048)
			(stroke
				(width 0.1)
				(type default)
			)
			(layer "F.Fab")
		)
		(fp_line
			(start 0.12065 -0.2794)
			(end 0.12065 -0.3048)
			(stroke
				(width 0.1)
				(type default)
			)
			(layer "F.Fab")
		)
		(fp_line
			(start 0.12065 -0.3048)
			(end 0.67945 -0.3048)
			(stroke
				(width 0.1)
				(type default)
			)
			(layer "F.Fab")
		)
		(fp_line
			(start 0.120396 0.3048)
			(end 0.120396 0.2794)
			(stroke
				(width 0.1)
				(type default)
			)
			(layer "F.Fab")
		)
		(fp_line
			(start 0.120396 0.2794)
			(end -0.12065 0.2794)
			(stroke
				(width 0.1)
				(type default)
			)
			(layer "F.Fab")
		)
		(fp_line
			(start -0.12065 0.3048)
			(end -0.67945 0.3048)
			(stroke
				(width 0.1)
				(type default)
			)
			(layer "F.Fab")
		)
		(fp_line
			(start -0.12065 0.2794)
			(end -0.12065 0.3048)
			(stroke
				(width 0.1)
				(type default)
			)
			(layer "F.Fab")
		)
		(fp_line
			(start -0.12065 -0.2794)
			(end 0.12065 -0.2794)
			(stroke
				(width 0.1)
				(type default)
			)
			(layer "F.Fab")
		)
		(fp_line
			(start -0.12065 -0.305054)
			(end -0.12065 -0.2794)
			(stroke
				(width 0.1)
				(type default)
			)
			(layer "F.Fab")
		)
		(fp_line
			(start -0.67945 0.3048)
			(end -0.67945 -0.305054)
			(stroke
				(width 0.1)
				(type default)
			)
			(layer "F.Fab")
		)
		(fp_line
			(start -0.67945 -0.305054)
			(end -0.12065 -0.305054)
			(stroke
				(width 0.1)
				(type default)
			)
			(layer "F.Fab")
		)
		(pad "1" smd circle
			(at -0.40005 0 180)
			(size 0 0)
			(layers "F.Cu" "F.Mask" "F.Paste")
			(net "RST_PEX_SSD7_PERST_N")
		)
		(pad "2" smd circle
			(at 0.40005 0 180)
			(size 0 0)
			(layers "F.Cu" "F.Mask" "F.Paste")
			(net "RST_PEX_SSD7_PERST_R_N")
		)
	)
	(footprint ""
		(layer "F.Cu")
		(at 241.542062 -199.736964)
		(property "Reference" "R6148"
			(at 0 0 0)
			(layer "F.SilkS")
			(hide yes)
			(effects
				(font
					(size 1.27 1.27)
				)
			)
		)
		(property "Value" ""
			(at 0 0 0)
			(layer "F.Fab")
			(effects
				(font
					(size 1.27 1.27)
				)
			)
		)
		(duplicate_pad_numbers_are_jumpers no)
		(fp_line
			(start -0.7874 -0.4064)
			(end 0.7874 -0.4064)
			(stroke
				(width 0.1524)
				(type default)
			)
			(layer "F.SilkS")
		)
		(fp_line
			(start -0.7874 0.4064)
			(end -0.7874 -0.4064)
			(stroke
				(width 0.1524)
				(type default)
			)
			(layer "F.SilkS")
		)
		(fp_line
			(start 0.7874 -0.4064)
			(end 0.7874 0.4064)
			(stroke
				(width 0.1524)
				(type default)
			)
			(layer "F.SilkS")
		)
		(fp_line
			(start 0.7874 0.4064)
			(end -0.7874 0.4064)
			(stroke
				(width 0.1524)
				(type default)
			)
			(layer "F.SilkS")
		)
		(fp_line
			(start -0.67945 -0.305054)
			(end -0.12065 -0.305054)
			(stroke
				(width 0.1)
				(type default)
			)
			(layer "F.Fab")
		)
		(fp_line
			(start -0.67945 0.3048)
			(end -0.67945 -0.305054)
			(stroke
				(width 0.1)
				(type default)
			)
			(layer "F.Fab")
		)
		(fp_line
			(start -0.12065 -0.305054)
			(end -0.12065 -0.2794)
			(stroke
				(width 0.1)
				(type default)
			)
			(layer "F.Fab")
		)
		(fp_line
			(start -0.12065 -0.2794)
			(end 0.12065 -0.2794)
			(stroke
				(width 0.1)
				(type default)
			)
			(layer "F.Fab")
		)
		(fp_line
			(start -0.12065 0.2794)
			(end -0.12065 0.3048)
			(stroke
				(width 0.1)
				(type default)
			)
			(layer "F.Fab")
		)
		(fp_line
			(start -0.12065 0.3048)
			(end -0.67945 0.3048)
			(stroke
				(width 0.1)
				(type default)
			)
			(layer "F.Fab")
		)
		(fp_line
			(start 0.120396 0.2794)
			(end -0.12065 0.2794)
			(stroke
				(width 0.1)
				(type default)
			)
			(layer "F.Fab")
		)
		(fp_line
			(start 0.120396 0.3048)
			(end 0.120396 0.2794)
			(stroke
				(width 0.1)
				(type default)
			)
			(layer "F.Fab")
		)
		(fp_line
			(start 0.12065 -0.3048)
			(end 0.67945 -0.3048)
			(stroke
				(width 0.1)
				(type default)
			)
			(layer "F.Fab")
		)
		(fp_line
			(start 0.12065 -0.2794)
			(end 0.12065 -0.3048)
			(stroke
				(width 0.1)
				(type default)
			)
			(layer "F.Fab")
		)
		(fp_line
			(start 0.67945 -0.3048)
			(end 0.67945 0.3048)
			(stroke
				(width 0.1)
				(type default)
			)
			(layer "F.Fab")
		)
		(fp_line
			(start 0.67945 0.3048)
			(end 0.120396 0.3048)
			(stroke
				(width 0.1)
				(type default)
			)
			(layer "F.Fab")
		)
		(pad "1" smd circle
			(at -0.40005 0)
			(size 0 0)
			(layers "F.Cu" "F.Mask" "F.Paste")
			(net "BIC_FWSPICS1_N")
		)
		(pad "2" smd circle
			(at 0.40005 0)
			(size 0 0)
			(layers "F.Cu" "F.Mask" "F.Paste")
			(net "P3V3_AUX")
		)
	)
	(footprint ""
		(layer "F.Cu")
		(at 198.765922 -77.889608 180)
		(property "Reference" "C904"
			(at 0 0 180)
			(layer "F.SilkS")
			(hide yes)
			(effects
				(font
					(size 1.27 1.27)
				)
			)
		)
		(property "Value" ""
			(at 0 0 180)
			(layer "F.Fab")
			(effects
				(font
					(size 1.27 1.27)
				)
			)
		)
		(duplicate_pad_numbers_are_jumpers no)
		(fp_line
			(start 0.7874 0.4064)
			(end -0.7874 0.4064)
			(stroke
				(width 0.1524)
				(type default)
			)
			(layer "F.SilkS")
		)
		(fp_line
			(start 0.7874 -0.4064)
			(end 0.7874 0.4064)
			(stroke
				(width 0.1524)
				(type default)
			)
			(layer "F.SilkS")
		)
		(fp_line
			(start -0.7874 0.4064)
			(end -0.7874 -0.4064)
			(stroke
				(width 0.1524)
				(type default)
			)
			(layer "F.SilkS")
		)
		(fp_line
			(start -0.7874 -0.4064)
			(end 0.7874 -0.4064)
			(stroke
				(width 0.1524)
				(type default)
			)
			(layer "F.SilkS")
		)
		(fp_line
			(start 0.67945 0.3048)
			(end 0.120396 0.3048)
			(stroke
				(width 0.1)
				(type default)
			)
			(layer "F.Fab")
		)
		(fp_line
			(start 0.67945 -0.3048)
			(end 0.67945 0.3048)
			(stroke
				(width 0.1)
				(type default)
			)
			(layer "F.Fab")
		)
		(fp_line
			(start 0.12065 -0.2794)
			(end 0.12065 -0.3048)
			(stroke
				(width 0.1)
				(type default)
			)
			(layer "F.Fab")
		)
		(fp_line
			(start 0.12065 -0.3048)
			(end 0.67945 -0.3048)
			(stroke
				(width 0.1)
				(type default)
			)
			(layer "F.Fab")
		)
		(fp_line
			(start 0.120396 0.3048)
			(end 0.120396 0.2794)
			(stroke
				(width 0.1)
				(type default)
			)
			(layer "F.Fab")
		)
		(fp_line
			(start 0.120396 0.2794)
			(end -0.12065 0.2794)
			(stroke
				(width 0.1)
				(type default)
			)
			(layer "F.Fab")
		)
		(fp_line
			(start -0.12065 0.3048)
			(end -0.67945 0.3048)
			(stroke
				(width 0.1)
				(type default)
			)
			(layer "F.Fab")
		)
		(fp_line
			(start -0.12065 0.2794)
			(end -0.12065 0.3048)
			(stroke
				(width 0.1)
				(type default)
			)
			(layer "F.Fab")
		)
		(fp_line
			(start -0.12065 -0.2794)
			(end 0.12065 -0.2794)
			(stroke
				(width 0.1)
				(type default)
			)
			(layer "F.Fab")
		)
		(fp_line
			(start -0.12065 -0.305054)
			(end -0.12065 -0.2794)
			(stroke
				(width 0.1)
				(type default)
			)
			(layer "F.Fab")
		)
		(fp_line
			(start -0.67945 0.3048)
			(end -0.67945 -0.305054)
			(stroke
				(width 0.1)
				(type default)
			)
			(layer "F.Fab")
		)
		(fp_line
			(start -0.67945 -0.305054)
			(end -0.12065 -0.305054)
			(stroke
				(width 0.1)
				(type default)
			)
			(layer "F.Fab")
		)
		(pad "1" smd circle
			(at -0.40005 0 180)
			(size 0 0)
			(layers "F.Cu" "F.Mask" "F.Paste")
			(net "P3V3_NIC3")
		)
		(pad "2" smd circle
			(at 0.40005 0 180)
			(size 0 0)
			(layers "F.Cu" "F.Mask" "F.Paste")
			(net "GND")
		)
	)
)
